G04*
G04 #@! TF.GenerationSoftware,Altium Limited,Altium Designer,23.7.1 (13)*
G04*
G04 Layer_Color=32768*
%FSLAX25Y25*%
%MOIN*%
G70*
G04*
G04 #@! TF.SameCoordinates,AF00DCEB-AC48-4C7C-91EA-99F42E284231*
G04*
G04*
G04 #@! TF.FilePolarity,Positive*
G04*
G01*
G75*
%ADD15C,0.00787*%
D15*
X595236Y-287728D02*
Y-283791D01*
Y-287728D02*
X597204D01*
Y-283791D01*
X595236D02*
X597204D01*
X545455Y-273819D02*
Y-269882D01*
X543487D02*
X545455D01*
X543487Y-273819D02*
Y-269882D01*
Y-273819D02*
X545455D01*
X581850Y-279460D02*
Y-275523D01*
X579882D02*
X581850D01*
X579882Y-279460D02*
Y-275523D01*
Y-279460D02*
X581850D01*
X579882Y-287334D02*
Y-283398D01*
Y-287334D02*
X581850D01*
Y-283398D01*
X579882D02*
X581850D01*
X554967Y-279770D02*
X558904D01*
X554967Y-281739D02*
Y-279770D01*
Y-281739D02*
X558904D01*
Y-279770D01*
X587192Y-282453D02*
X592113D01*
Y-277532D01*
X587192D02*
X592113D01*
X587192Y-282453D02*
Y-277532D01*
X597204Y-280248D02*
Y-276311D01*
X595236D02*
X597204D01*
X595236Y-280248D02*
Y-276311D01*
Y-280248D02*
X597204D01*
X476888Y-302356D02*
Y-298418D01*
Y-302356D02*
X478857D01*
Y-298418D01*
X476888D02*
X478857D01*
X482283Y-266732D02*
Y-264764D01*
X478346Y-266732D02*
X482283D01*
X478346D02*
Y-264764D01*
X482283D01*
X188779Y-92520D02*
X190748D01*
Y-96457D02*
Y-92520D01*
X188779Y-96457D02*
X190748D01*
X188779D02*
Y-92520D01*
X150766Y5912D02*
X152735D01*
Y1975D02*
Y5912D01*
X150766Y1975D02*
X152735D01*
X150766D02*
Y5912D01*
X499213Y-253346D02*
Y-251378D01*
X495276Y-253346D02*
X499213D01*
X495276D02*
Y-251378D01*
X499213D01*
X505709Y-261120D02*
Y-259152D01*
X509646D01*
Y-261120D02*
Y-259152D01*
X505709Y-261120D02*
X509646D01*
X499606Y-260827D02*
Y-258858D01*
X495669Y-260827D02*
X499606D01*
X495669D02*
Y-258858D01*
X499606D01*
X567913Y-262104D02*
Y-260135D01*
X563976Y-262104D02*
X567913D01*
X563976D02*
Y-260135D01*
X567913D01*
X571358Y-262106D02*
Y-260138D01*
X575295D01*
Y-262106D02*
Y-260138D01*
X571358Y-262106D02*
X575295D01*
X208465Y787D02*
X210433D01*
X208465D02*
Y4724D01*
X210433D01*
Y787D02*
Y4724D01*
X202854Y-4921D02*
X204823D01*
X202854D02*
Y-984D01*
X204823D01*
Y-4921D02*
Y-984D01*
X213189Y-5118D02*
X215158D01*
X213189D02*
Y-1181D01*
X215158D01*
Y-5118D02*
Y-1181D01*
X203553Y-73032D02*
X205521D01*
Y-76968D02*
Y-73032D01*
X203553Y-76968D02*
X205521D01*
X203553D02*
Y-73032D01*
X213189Y-72835D02*
X215158D01*
Y-76772D02*
Y-72835D01*
X213189Y-76772D02*
X215158D01*
X213189D02*
Y-72835D01*
X408071Y-128445D02*
X412402D01*
X408071Y-130610D02*
Y-128445D01*
Y-130610D02*
X412402D01*
Y-128445D01*
X413779Y-123425D02*
X417717D01*
X413779Y-125394D02*
Y-123425D01*
Y-125394D02*
X417717D01*
Y-123425D01*
X427953Y-131693D02*
X431890D01*
X427953Y-133661D02*
Y-131693D01*
Y-133661D02*
X431890D01*
Y-131693D01*
X55741Y-35728D02*
X57907D01*
X55741D02*
Y-31398D01*
X57907D01*
Y-35728D02*
Y-31398D01*
X111024Y-15157D02*
X114961D01*
X111024Y-17126D02*
Y-15157D01*
Y-17126D02*
X114961D01*
Y-15157D01*
X93701Y-78150D02*
Y-76181D01*
X97638D01*
Y-78150D02*
Y-76181D01*
X93701Y-78150D02*
X97638D01*
X107677Y-44230D02*
X109646D01*
Y-48167D02*
Y-44230D01*
X107677Y-48167D02*
X109646D01*
X107677D02*
Y-44230D01*
X280906Y-193307D02*
X282874D01*
Y-197244D02*
Y-193307D01*
X280906Y-197244D02*
X282874D01*
X280906D02*
Y-193307D01*
X337402Y-291929D02*
X341339D01*
X337402Y-293898D02*
Y-291929D01*
Y-293898D02*
X341339D01*
Y-291929D01*
X318504Y-292717D02*
X322441D01*
X318504Y-294685D02*
Y-292717D01*
Y-294685D02*
X322441D01*
Y-292717D01*
X323622Y-238779D02*
X327559D01*
X323622Y-240748D02*
Y-238779D01*
Y-240748D02*
X327559D01*
Y-238779D01*
X375984Y-233957D02*
X379921D01*
Y-231988D01*
X375984D02*
X379921D01*
X375984Y-233957D02*
Y-231988D01*
X552756Y-327461D02*
X561417D01*
X552756Y-333169D02*
Y-327461D01*
Y-333169D02*
X561417D01*
Y-327461D01*
X528888Y-331692D02*
X537550D01*
Y-325983D01*
X528888D02*
X537550D01*
X528888Y-331692D02*
Y-325983D01*
X561811Y-312697D02*
X570472D01*
Y-306988D01*
X561811D02*
X570472D01*
X561811Y-312697D02*
Y-306988D01*
X528888Y-315127D02*
X537550D01*
Y-309418D01*
X528888D02*
X537550D01*
X528888Y-315127D02*
Y-309418D01*
X117717Y-33366D02*
X126378D01*
X117717Y-39075D02*
Y-33366D01*
Y-39075D02*
X126378D01*
Y-33366D01*
X121073Y-77429D02*
X129734D01*
Y-71720D01*
X121073D02*
X129734D01*
X121073Y-77429D02*
Y-71720D01*
X152364Y-73927D02*
Y-68218D01*
X143702Y-73927D02*
X152364D01*
X143702D02*
Y-68218D01*
X152364D01*
X145778Y-41387D02*
X151486D01*
Y-50049D02*
Y-41387D01*
X145778Y-50049D02*
X151486D01*
X145778D02*
Y-41387D01*
X611024Y-239567D02*
X614961D01*
Y-237598D01*
X611024D02*
X614961D01*
X611024Y-239567D02*
Y-237598D01*
X612357Y-232087D02*
X616294D01*
Y-230118D01*
X612357D02*
X616294D01*
X612357Y-232087D02*
Y-230118D01*
X612303Y-303740D02*
X616240D01*
Y-301772D01*
X612303D02*
X616240D01*
X612303Y-303740D02*
Y-301772D01*
X382413Y-133071D02*
X389500D01*
X382413Y-137008D02*
Y-133071D01*
Y-137008D02*
X389500D01*
Y-133071D01*
X66496Y-59517D02*
Y-52430D01*
X62559D02*
X66496D01*
X62559Y-59517D02*
Y-52430D01*
Y-59517D02*
X66496D01*
X95079Y-44882D02*
X97047D01*
Y-48819D02*
Y-44882D01*
X95079Y-48819D02*
X97047D01*
X95079D02*
Y-44882D01*
X100000Y-42913D02*
X103937D01*
Y-50000D02*
Y-42913D01*
X100000Y-50000D02*
X103937D01*
X100000D02*
Y-42913D01*
X607480Y-62992D02*
X614567D01*
X607480Y-66929D02*
Y-62992D01*
Y-66929D02*
X614567D01*
Y-62992D01*
X149445Y-123228D02*
X153382D01*
X149445Y-125197D02*
Y-123228D01*
Y-125197D02*
X153382D01*
Y-123228D01*
X162992Y-105118D02*
Y-98032D01*
Y-105118D02*
X166929D01*
Y-98032D01*
X162992D02*
X166929D01*
X152165Y-103543D02*
Y-99606D01*
Y-103543D02*
X154134D01*
Y-99606D01*
X152165D02*
X154134D01*
X159646Y-101958D02*
Y-98021D01*
X157677D02*
X159646D01*
X157677Y-101958D02*
Y-98021D01*
Y-101958D02*
X159646D01*
M02*
